(kicad_pcb
	(version 20241229)
	(generator "pcbnew")
	(generator_version "9.0")
	(general
		(thickness 1.62)
		(legacy_teardrops no)
	)
	(paper "A3")
	(title_block
		(title "COM Express 7 Baseboard")
		(date "2025-02-04")
		(rev "1.1.2")
		(company "Antmicro Ltd")
		(comment 1 "www.antmicro.com")
		(comment 9 "footprints 119-122 of 802")
	)
	(layers
		(0 "F.Cu" signal)
		(4 "In1.Cu" signal)
		(6 "In2.Cu" signal)
		(8 "In3.Cu" signal)
		(10 "In4.Cu" signal)
		(12 "In5.Cu" signal)
		(14 "In6.Cu" signal)
		(2 "B.Cu" signal)
		(9 "F.Adhes" user "F.Adhesive")
		(11 "B.Adhes" user "B.Adhesive")
		(13 "F.Paste" user)
		(15 "B.Paste" user)
		(5 "F.SilkS" user "F.Silkscreen")
		(7 "B.SilkS" user "B.Silkscreen")
		(1 "F.Mask" user)
		(3 "B.Mask" user)
		(17 "Dwgs.User" user "User.Drawings")
		(19 "Cmts.User" user "User.Comments")
		(21 "Eco1.User" user "User.Eco1")
		(23 "Eco2.User" user "User.Eco2")
		(25 "Edge.Cuts" user)
		(27 "Margin" user)
		(31 "F.CrtYd" user "F.Courtyard")
		(29 "B.CrtYd" user "B.Courtyard")
		(35 "F.Fab" user)
		(33 "B.Fab" user)
	)
	(footprint "antmicro-footprints:LED_0603_1608Metric_Y"
		(layer "F.Cu")
		(at 146.49 156.17 180)
		(descr "LED SMD 0603 Yellow")
		(tags "LED SMD 0603 Yellow")
		(property "Reference" "D4"
			(at 2.69 -0.44 180)
			(layer "F.SilkS")
			(effects
				(font
					(size 0.7 0.7)
					(thickness 0.15)
				)
				(justify left bottom)
			)
		)
		(property "Value" "LED_Y_0603_LTST-C191KSKT"
			(at 0 1.6 180)
			(layer "F.Fab")
			(effects
				(font
					(size 0.7 0.7)
					(thickness 0.15)
				)
				(justify left bottom)
			)
		)
		(property "Datasheet" "https://optoelectronics.liteon.com/upload/download/DS22-2000-224/LTST-C191KSKT.PDF"
			(at 0 0 180)
			(layer "F.Fab")
			(hide yes)
			(effects
				(font
					(size 1.27 1.27)
					(thickness 0.15)
				)
			)
		)
		(property "Author" "Antmicro"
			(at 292.98 312.34 0)
			(layer "F.Fab")
			(hide yes)
			(effects
				(font
					(size 1 1)
					(thickness 0.15)
				)
			)
		)
		(property "Color" "Yellow"
			(at 292.98 312.34 0)
			(layer "F.Fab")
			(hide yes)
			(effects
				(font
					(size 1 1)
					(thickness 0.15)
				)
			)
		)
		(property "License" "Apache-2.0"
			(at 292.98 312.34 0)
			(layer "F.Fab")
			(hide yes)
			(effects
				(font
					(size 1 1)
					(thickness 0.15)
				)
			)
		)
		(property "MPN" "LTST-C191KSKT"
			(at 292.98 312.34 0)
			(layer "F.Fab")
			(hide yes)
			(effects
				(font
					(size 1 1)
					(thickness 0.15)
				)
			)
		)
		(property "Manufacturer" "Lite-On"
			(at 292.98 312.34 0)
			(layer "F.Fab")
			(hide yes)
			(effects
				(font
					(size 1 1)
					(thickness 0.15)
				)
			)
		)
		(sheetname "2xSFP+")
		(sheetfile "2xSFP+.kicad_sch")
		(attr smd)
		(fp_line
			(start 0.22 0.35)
			(end -0.22 0.35)
			(stroke
				(width 0.15)
				(type solid)
			)
			(layer "F.SilkS")
		)
		(fp_line
			(start 0.22 -0.35)
			(end -0.22 -0.35)
			(stroke
				(width 0.15)
				(type solid)
			)
			(layer "F.SilkS")
		)
		(fp_line
			(start 0.105328 0.201008)
			(end 0.105328 -0.198992)
			(stroke
				(width 0.1)
				(type solid)
			)
			(layer "F.SilkS")
		)
		(fp_line
			(start 0.105328 0.201008)
			(end -0.094672 0.001008)
			(stroke
				(width 0.1)
				(type solid)
			)
			(layer "F.SilkS")
		)
		(fp_line
			(start 0.105328 0.001008)
			(end 0.24 0.001)
			(stroke
				(width 0.1)
				(type solid)
			)
			(layer "F.SilkS")
		)
		(fp_line
			(start -0.094672 0.201008)
			(end -0.094672 -0.198992)
			(stroke
				(width 0.1)
				(type solid)
			)
			(layer "F.SilkS")
		)
		(fp_line
			(start -0.094672 0.001008)
			(end 0.105328 -0.198992)
			(stroke
				(width 0.1)
				(type solid)
			)
			(layer "F.SilkS")
		)
		(fp_line
			(start -0.094672 0.001008)
			(end -0.24 0.001008)
			(stroke
				(width 0.1)
				(type solid)
			)
			(layer "F.SilkS")
		)
		(fp_line
			(start -1.18 -0.319)
			(end -1.18 0.321)
			(stroke
				(width 0.15)
				(type solid)
			)
			(layer "F.SilkS")
		)
		(fp_rect
			(start 1.25 0.65)
			(end -1.25 -0.65)
			(stroke
				(width 0.05)
				(type solid)
			)
			(fill no)
			(layer "F.CrtYd")
		)
		(fp_line
			(start 0.599 0)
			(end 0.201 0)
			(stroke
				(width 0.15)
				(type solid)
			)
			(layer "F.Fab")
		)
		(fp_line
			(start 0.201 0.2)
			(end 0.201 0)
			(stroke
				(width 0.15)
				(type solid)
			)
			(layer "F.Fab")
		)
		(fp_line
			(start 0.201 0)
			(end 0.201 -0.202)
			(stroke
				(width 0.15)
				(type solid)
			)
			(layer "F.Fab")
		)
		(fp_line
			(start 0.201 -0.202)
			(end -0.101 0)
			(stroke
				(width 0.15)
				(type solid)
			)
			(layer "F.Fab")
		)
		(fp_line
			(start -0.101 0)
			(end 0.201 0.2)
			(stroke
				(width 0.15)
				(type solid)
			)
			(layer "F.Fab")
		)
		(fp_line
			(start -0.199 0.2)
			(end -0.199 0.1)
			(stroke
				(width 0.15)
				(type solid)
			)
			(layer "F.Fab")
		)
		(fp_line
			(start -0.199 0)
			(end -0.597 0)
			(stroke
				(width 0.15)
				(type solid)
			)
			(layer "F.Fab")
		)
		(fp_line
			(start -0.199 -0.202)
			(end -0.199 0.1)
			(stroke
				(width 0.15)
				(type solid)
			)
			(layer "F.Fab")
		)
		(fp_rect
			(start 0.848 0.4)
			(end -0.85 -0.402)
			(stroke
				(width 0.15)
				(type solid)
			)
			(fill no)
			(layer "F.Fab")
		)
		(pad "1" smd roundrect
			(at -0.7 0)
			(size 0.8 1)
			(layers "F.Cu" "F.Mask" "F.Paste")
			(roundrect_rratio 0.2)
			(net 899 "Net-(D4-C)")
			(pinfunction "C")
			(pintype "passive")
			(teardrops
				(best_length_ratio 0.2)
				(max_length 1)
				(best_width_ratio 0.9)
				(max_width 2)
				(curved_edges yes)
				(filter_ratio 0.9)
				(enabled yes)
				(allow_two_segments yes)
				(prefer_zone_connections yes)
			)
		)
		(pad "2" smd roundrect
			(at 0.7 0)
			(size 0.8 1)
			(layers "F.Cu" "F.Mask" "F.Paste")
			(roundrect_rratio 0.2)
			(net 2 "+3V3")
			(pinfunction "A")
			(pintype "passive")
			(teardrops
				(best_length_ratio 0.2)
				(max_length 1)
				(best_width_ratio 0.9)
				(max_width 2)
				(curved_edges yes)
				(filter_ratio 0.9)
				(enabled yes)
				(allow_two_segments yes)
				(prefer_zone_connections yes)
			)
		)
	)
	(footprint "antmicro-footprints:R_0402_1005Metric"
		(layer "F.Cu")
		(at 252.615 83.174999 180)
		(descr "Resistor SMD 0402")
		(tags "resistor SMD 0402")
		(property "Reference" "R145"
			(at 0.825 -0.435001 0)
			(layer "F.SilkS")
			(effects
				(font
					(size 0.7 0.7)
					(thickness 0.15)
				)
				(justify right bottom)
			)
		)
		(property "Value" "R_10k_0402"
			(at -1.011843 1.772047 0)
			(layer "F.Fab")
			(effects
				(font
					(size 0.7 0.7)
					(thickness 0.15)
				)
				(justify right bottom)
			)
		)
		(property "Datasheet" "https://www.bourns.com/docs/product-datasheets/cr.pdf"
			(at 0 0 180)
			(layer "F.Fab")
			(hide yes)
			(effects
				(font
					(size 1.27 1.27)
					(thickness 0.15)
				)
			)
		)
		(property "Author" "Antmicro"
			(at 505.23 166.349998 0)
			(layer "F.Fab")
			(hide yes)
			(effects
				(font
					(size 1 1)
					(thickness 0.15)
				)
			)
		)
		(property "License" "Apache-2.0"
			(at 505.23 166.349998 0)
			(layer "F.Fab")
			(hide yes)
			(effects
				(font
					(size 1 1)
					(thickness 0.15)
				)
			)
		)
		(property "MPN" "CR0402-FX-1002GLF"
			(at 505.23 166.349998 0)
			(layer "F.Fab")
			(hide yes)
			(effects
				(font
					(size 1 1)
					(thickness 0.15)
				)
			)
		)
		(property "Manufacturer" "Bourns"
			(at 505.23 166.349998 0)
			(layer "F.Fab")
			(hide yes)
			(effects
				(font
					(size 1 1)
					(thickness 0.15)
				)
			)
		)
		(property "Public" "False"
			(at 505.23 166.349998 0)
			(layer "F.Fab")
			(hide yes)
			(effects
				(font
					(size 1 1)
					(thickness 0.15)
				)
			)
		)
		(property "Tolerance" "1%"
			(at 505.23 166.349998 0)
			(layer "F.Fab")
			(hide yes)
			(effects
				(font
					(size 1 1)
					(thickness 0.15)
				)
			)
		)
		(property "Val" "10k"
			(at 505.23 166.349998 0)
			(layer "F.Fab")
			(hide yes)
			(effects
				(font
					(size 1 1)
					(thickness 0.15)
				)
			)
		)
		(sheetname "Misc")
		(sheetfile "misc.kicad_sch")
		(attr smd)
		(fp_rect
			(start -0.925 -0.47)
			(end 0.925 0.47)
			(stroke
				(width 0.05)
				(type default)
			)
			(fill no)
			(layer "F.CrtYd")
		)
		(fp_rect
			(start -0.5 -0.25)
			(end 0.5 0.25)
			(stroke
				(width 0.15)
				(type solid)
			)
			(fill no)
			(layer "F.Fab")
		)
		(pad "1" smd roundrect
			(at -0.48 0 180)
			(size 0.59 0.64)
			(layers "F.Cu" "F.Mask" "F.Paste")
			(roundrect_rratio 0.25)
			(net 589 "/Misc/~{ADDRSEL}")
			(pintype "passive")
			(teardrops
				(best_length_ratio 0.2)
				(max_length 1)
				(best_width_ratio 0.9)
				(max_width 2)
				(curved_edges yes)
				(filter_ratio 0.9)
				(enabled yes)
				(allow_two_segments yes)
				(prefer_zone_connections yes)
			)
		)
		(pad "2" smd roundrect
			(at 0.48 0 180)
			(size 0.59 0.64)
			(layers "F.Cu" "F.Mask" "F.Paste")
			(roundrect_rratio 0.25)
			(net 2 "+3V3")
			(pintype "passive")
			(teardrops
				(best_length_ratio 0.2)
				(max_length 1)
				(best_width_ratio 0.9)
				(max_width 2)
				(curved_edges yes)
				(filter_ratio 0.9)
				(enabled yes)
				(allow_two_segments yes)
				(prefer_zone_connections yes)
			)
		)
	)
	(footprint "antmicro-footprints:R_0402_1005Metric"
		(layer "F.Cu")
		(at 219.432501 133.1 90)
		(descr "Resistor SMD 0402")
		(tags "resistor SMD 0402")
		(property "Reference" "R316"
			(at -1.31 2.317499 90)
			(layer "F.SilkS")
			(effects
				(font
					(size 0.7 0.7)
					(thickness 0.15)
				)
				(justify left bottom)
			)
		)
		(property "Value" "R_0R_0402"
			(at -1.011843 1.772047 90)
			(layer "F.Fab")
			(effects
				(font
					(size 0.7 0.7)
					(thickness 0.15)
				)
				(justify left bottom)
			)
		)
		(property "Datasheet" "https://industrial.panasonic.com/cdbs/www-data/pdf/RDA0000/AOA0000C301.pdf"
			(at 0 0 90)
			(layer "F.Fab")
			(hide yes)
			(effects
				(font
					(size 1.27 1.27)
					(thickness 0.15)
				)
			)
		)
		(property "Author" "Antmicro"
			(at 352.532501 -86.332501 0)
			(layer "F.Fab")
			(hide yes)
			(effects
				(font
					(size 1 1)
					(thickness 0.15)
				)
			)
		)
		(property "Current" "1A"
			(at 352.532501 -86.332501 0)
			(layer "F.Fab")
			(hide yes)
			(effects
				(font
					(size 1 1)
					(thickness 0.15)
				)
			)
		)
		(property "License" "Apache-2.0"
			(at 352.532501 -86.332501 0)
			(layer "F.Fab")
			(hide yes)
			(effects
				(font
					(size 1 1)
					(thickness 0.15)
				)
			)
		)
		(property "MPN" "ERJ2GE0R00X"
			(at 352.532501 -86.332501 0)
			(layer "F.Fab")
			(hide yes)
			(effects
				(font
					(size 1 1)
					(thickness 0.15)
				)
			)
		)
		(property "Manufacturer" "Panasonic"
			(at 352.532501 -86.332501 0)
			(layer "F.Fab")
			(hide yes)
			(effects
				(font
					(size 1 1)
					(thickness 0.15)
				)
			)
		)
		(property "Public" "False"
			(at 352.532501 -86.332501 0)
			(layer "F.Fab")
			(hide yes)
			(effects
				(font
					(size 1 1)
					(thickness 0.15)
				)
			)
		)
		(property "Tolerance" ""
			(at 352.532501 -86.332501 0)
			(layer "F.Fab")
			(hide yes)
			(effects
				(font
					(size 1 1)
					(thickness 0.15)
				)
			)
		)
		(property "Val" "0R"
			(at 352.532501 -86.332501 0)
			(layer "F.Fab")
			(hide yes)
			(effects
				(font
					(size 1 1)
					(thickness 0.15)
				)
			)
		)
		(sheetname "PCIe misc")
		(sheetfile "pcie_misc.kicad_sch")
		(attr smd dnp)
		(fp_rect
			(start -0.925 -0.47)
			(end 0.925 0.47)
			(stroke
				(width 0.05)
				(type default)
			)
			(fill no)
			(layer "F.CrtYd")
		)
		(fp_rect
			(start -0.5 -0.25)
			(end 0.5 0.25)
			(stroke
				(width 0.15)
				(type solid)
			)
			(fill no)
			(layer "F.Fab")
		)
		(pad "1" smd roundrect
			(at -0.48 0 90)
			(size 0.59 0.64)
			(layers "F.Cu" "F.Mask" "F.Paste")
			(roundrect_rratio 0.25)
			(net 526 "/Backplane/~{PRSNT}")
			(pintype "passive")
			(teardrops
				(best_length_ratio 0.2)
				(max_length 1)
				(best_width_ratio 0.9)
				(max_width 2)
				(curved_edges yes)
				(filter_ratio 0.9)
				(enabled yes)
				(allow_two_segments yes)
				(prefer_zone_connections yes)
			)
		)
		(pad "2" smd roundrect
			(at 0.48 0 90)
			(size 0.59 0.64)
			(layers "F.Cu" "F.Mask" "F.Paste")
			(roundrect_rratio 0.25)
			(net 605 "Net-(U37-~{OE3})")
			(pintype "passive")
			(teardrops
				(best_length_ratio 0.2)
				(max_length 1)
				(best_width_ratio 0.9)
				(max_width 2)
				(curved_edges yes)
				(filter_ratio 0.9)
				(enabled yes)
				(allow_two_segments yes)
				(prefer_zone_connections yes)
			)
		)
	)
	(footprint "antmicro-footprints:C_0402_1005Metric"
		(layer "F.Cu")
		(at 190.720296 137.31618 135)
		(descr "Capacitor SMD 0402")
		(tags "capacitor SMD 0402")
		(property "Reference" "C118"
			(at 3.844168 0.29978 135)
			(layer "F.SilkS")
			(effects
				(font
					(size 0.7 0.7)
					(thickness 0.15)
				)
				(justify left top)
			)
		)
		(property "Value" "C_100n_0402"
			(at -1.022927 2.155213 135)
			(layer "F.Fab")
			(effects
				(font
					(size 0.7 0.7)
					(thickness 0.15)
				)
				(justify left top)
			)
		)
		(property "Datasheet" "https://www.murata.com/products/productdetail?partno=GRM155R61H104KE14%23"
			(at 0 0 135)
			(layer "B.Fab")
			(hide yes)
			(effects
				(font
					(size 1.27 1.27)
					(thickness 0.15)
				)
				(justify mirror)
			)
		)
		(property "Author" "Antmicro"
			(at 326.514 57.788 45)
			(layer "F.Fab")
			(hide yes)
			(effects
				(font
					(size 1 1)
					(thickness 0.15)
				)
			)
		)
		(property "Dielectric" "X5R"
			(at 326.514 57.788 45)
			(layer "F.Fab")
			(hide yes)
			(effects
				(font
					(size 1 1)
					(thickness 0.15)
				)
			)
		)
		(property "License" "Apache-2.0"
			(at 326.514 57.788 45)
			(layer "F.Fab")
			(hide yes)
			(effects
				(font
					(size 1 1)
					(thickness 0.15)
				)
			)
		)
		(property "MPN" "GRM155R61H104KE14D"
			(at 326.514 57.788 45)
			(layer "F.Fab")
			(hide yes)
			(effects
				(font
					(size 1 1)
					(thickness 0.15)
				)
			)
		)
		(property "Manufacturer" "Murata"
			(at 326.514 57.788 45)
			(layer "F.Fab")
			(hide yes)
			(effects
				(font
					(size 1 1)
					(thickness 0.15)
				)
			)
		)
		(property "Public" "False"
			(at 326.514 57.788 45)
			(layer "F.Fab")
			(hide yes)
			(effects
				(font
					(size 1 1)
					(thickness 0.15)
				)
			)
		)
		(property "Val" "100n"
			(at 326.514 57.788 45)
			(layer "F.Fab")
			(hide yes)
			(effects
				(font
					(size 1 1)
					(thickness 0.15)
				)
			)
		)
		(property "Voltage" "50V"
			(at 326.514 57.788 45)
			(layer "F.Fab")
			(hide yes)
			(effects
				(font
					(size 1 1)
					(thickness 0.15)
				)
			)
		)
		(sheetname "PCIe redriver")
		(sheetfile "pcie_redriver.kicad_sch")
		(attr smd)
		(fp_poly
			(pts
				(xy -0.925 -0.47) (xy 0.925 -0.47) (xy 0.925 0.47) (xy -0.925 0.47)
			)
			(stroke
				(width 0.05)
				(type default)
			)
			(fill no)
			(layer "F.CrtYd")
		)
		(fp_line
			(start 0.504 -0.25)
			(end 0.504 0.248)
			(stroke
				(width 0.15)
				(type solid)
			)
			(layer "F.Fab")
		)
		(fp_line
			(start 0.504 0.248)
			(end -0.494 0.248)
			(stroke
				(width 0.15)
				(type solid)
			)
			(layer "F.Fab")
		)
		(fp_line
			(start -0.494 -0.25)
			(end 0.504 -0.25)
			(stroke
				(width 0.15)
				(type solid)
			)
			(layer "F.Fab")
		)
		(fp_line
			(start -0.494 0.248)
			(end -0.494 -0.25)
			(stroke
				(width 0.15)
				(type solid)
			)
			(layer "F.Fab")
		)
		(pad "1" smd roundrect
			(at -0.48 0 135)
			(size 0.59 0.64)
			(layers "F.Cu" "F.Mask" "F.Paste")
			(roundrect_rratio 0.25)
			(net 1 "GND")
			(pintype "passive")
			(teardrops
				(best_length_ratio 0.2)
				(max_length 1)
				(best_width_ratio 0.9)
				(max_width 2)
				(curved_edges yes)
				(filter_ratio 0.9)
				(enabled yes)
				(allow_two_segments yes)
				(prefer_zone_connections yes)
			)
		)
		(pad "2" smd roundrect
			(at 0.48 0 135)
			(size 0.59 0.64)
			(layers "F.Cu" "F.Mask" "F.Paste")
			(roundrect_rratio 0.25)
			(net 2 "+3V3")
			(pintype "passive")
			(teardrops
				(best_length_ratio 0.2)
				(max_length 1)
				(best_width_ratio 0.9)
				(max_width 2)
				(curved_edges yes)
				(filter_ratio 0.9)
				(enabled yes)
				(allow_two_segments yes)
				(prefer_zone_connections yes)
			)
		)
	)
)
